(kicad_pcb
	(version 20260206)
	(generator "pcbnew")
	(generator_version "10.0")
	(general
		(thickness 1.6)
		(legacy_teardrops no)
	)
	(paper "A4")
	(title_block
		(title "9054_F0T_PDB_BD_GPU_F_V04_1213_1550_OCP.brd")
		(comment 1 "Grand Teton / footprints 268-272 of 608")
	)
	(layers
		(0 "F.Cu" signal "TOP")
		(4 "In1.Cu" signal "GND")
		(6 "In2.Cu" signal "IN1")
		(8 "In3.Cu" signal "GND1")
		(10 "In4.Cu" signal "VCC")
		(12 "In5.Cu" signal "VCC1")
		(14 "In6.Cu" signal "GND2")
		(16 "In7.Cu" signal "IN2")
		(18 "In8.Cu" signal "GND3")
		(2 "B.Cu" signal "BOTTOM")
		(9 "F.Adhes" user "F.Adhesive")
		(11 "B.Adhes" user "B.Adhesive")
		(13 "F.Paste" user "Package Geometry/Pastemask Top")
		(15 "B.Paste" user "Package Geometry/Pastemask Bottom")
		(5 "F.SilkS" user "Ref Des/Silkscreen Top")
		(7 "B.SilkS" user "Ref Des/Silkscreen Bottom")
		(1 "F.Mask" user "Board Geometry/Soldermask Top")
		(3 "B.Mask" user "Board Geometry/Soldermask Bottom")
		(17 "Dwgs.User" user "User.Drawings")
		(19 "Cmts.User" user "User.Comments")
		(21 "Eco1.User" user "User.Eco1")
		(23 "Eco2.User" user "User.Eco2")
		(25 "Edge.Cuts" user "Board Geometry/Outline")
		(27 "Margin" user)
		(31 "F.CrtYd" user "Package Geometry/Place Bound Top")
		(29 "B.CrtYd" user "Package Geometry/Place Bound Bottom")
		(35 "F.Fab" user "Ref Des/Assembly Top")
		(33 "B.Fab" user "Ref Des/Assembly Bottom")
	)
	(footprint ""
		(layer "F.Cu")
		(at 449.199 -48.514)
		(property "Reference" "U37"
			(at 1.8415 1.30937 0)
			(unlocked yes)
			(layer "F.SilkS")
			(effects
				(font
					(size 0.7874 0.5842)
					(thickness 0.1524)
				)
				(justify left)
			)
		)
		(property "Value" ""
			(at 0 0 0)
			(layer "F.Fab")
			(effects
				(font
					(size 1.27 1.27)
				)
			)
		)
		(duplicate_pad_numbers_are_jumpers no)
		(fp_line
			(start -1.603248 -1.500124)
			(end 1.603248 -1.500124)
			(stroke
				(width 0.1524)
				(type default)
			)
			(layer "F.SilkS")
		)
		(fp_line
			(start -1.603248 1.500124)
			(end -1.603248 -1.500124)
			(stroke
				(width 0.1524)
				(type default)
			)
			(layer "F.SilkS")
		)
		(fp_line
			(start 1.603248 -1.500124)
			(end 1.603248 1.500124)
			(stroke
				(width 0.1524)
				(type default)
			)
			(layer "F.SilkS")
		)
		(fp_line
			(start 1.603248 1.500124)
			(end -1.603248 1.500124)
			(stroke
				(width 0.1524)
				(type default)
			)
			(layer "F.SilkS")
		)
		(fp_line
			(start -1.249934 -1.169924)
			(end -1.249934 -0.729996)
			(stroke
				(width 0.1)
				(type default)
			)
			(layer "F.Fab")
		)
		(fp_line
			(start -1.249934 -0.729996)
			(end -0.6985 -0.729996)
			(stroke
				(width 0.1)
				(type default)
			)
			(layer "F.Fab")
		)
		(fp_line
			(start -1.249934 0.729996)
			(end -1.249934 1.169924)
			(stroke
				(width 0.1)
				(type default)
			)
			(layer "F.Fab")
		)
		(fp_line
			(start -1.249934 1.169924)
			(end -0.700024 1.169924)
			(stroke
				(width 0.1)
				(type default)
			)
			(layer "F.Fab")
		)
		(fp_line
			(start -0.700024 -1.500124)
			(end -0.700024 -1.169924)
			(stroke
				(width 0.1)
				(type default)
			)
			(layer "F.Fab")
		)
		(fp_line
			(start -0.700024 -1.169924)
			(end -1.249934 -1.169924)
			(stroke
				(width 0.1)
				(type default)
			)
			(layer "F.Fab")
		)
		(fp_line
			(start -0.700024 1.169924)
			(end -0.700024 1.500124)
			(stroke
				(width 0.1)
				(type default)
			)
			(layer "F.Fab")
		)
		(fp_line
			(start -0.700024 1.500124)
			(end 0.700024 1.500124)
			(stroke
				(width 0.1)
				(type default)
			)
			(layer "F.Fab")
		)
		(fp_line
			(start -0.6985 -0.729996)
			(end -0.6985 0.729996)
			(stroke
				(width 0.1)
				(type default)
			)
			(layer "F.Fab")
		)
		(fp_line
			(start -0.6985 0.729996)
			(end -1.249934 0.729996)
			(stroke
				(width 0.1)
				(type default)
			)
			(layer "F.Fab")
		)
		(fp_line
			(start 0.700024 -1.500124)
			(end -0.700024 -1.500124)
			(stroke
				(width 0.1)
				(type default)
			)
			(layer "F.Fab")
		)
		(fp_line
			(start 0.700024 -0.219964)
			(end 0.700024 -1.500124)
			(stroke
				(width 0.1)
				(type default)
			)
			(layer "F.Fab")
		)
		(fp_line
			(start 0.700024 0.219964)
			(end 1.249934 0.219964)
			(stroke
				(width 0.1)
				(type default)
			)
			(layer "F.Fab")
		)
		(fp_line
			(start 0.700024 1.500124)
			(end 0.700024 0.219964)
			(stroke
				(width 0.1)
				(type default)
			)
			(layer "F.Fab")
		)
		(fp_line
			(start 1.249934 -0.219964)
			(end 0.700024 -0.219964)
			(stroke
				(width 0.1)
				(type default)
			)
			(layer "F.Fab")
		)
		(fp_line
			(start 1.249934 0.219964)
			(end 1.249934 -0.219964)
			(stroke
				(width 0.1)
				(type default)
			)
			(layer "F.Fab")
		)
		(fp_rect
			(start -0.700024 1.500124)
			(end 0.700024 -1.500124)
			(stroke
				(width 0)
				(type default)
			)
			(fill no)
			(layer "F.Fab")
		)
		(pad "D" smd rect
			(at 0.999998 0 270)
			(size 0.8128 0.9144)
			(layers "F.Cu" "F.Mask" "F.Paste")
			(net "PWRGD_P3V3_HPDB_R")
		)
		(pad "G" smd rect
			(at -0.999998 -0.94996 270)
			(size 0.8128 0.9144)
			(layers "F.Cu" "F.Mask" "F.Paste")
			(net "PWRGD_P3V3_HPDB_R_N")
		)
		(pad "S" smd rect
			(at -0.999998 0.94996 270)
			(size 0.8128 0.9144)
			(layers "F.Cu" "F.Mask" "F.Paste")
			(net "GND")
		)
	)
	(footprint ""
		(layer "F.Cu")
		(at 230.3526 -91.9988 180)
		(property "Reference" "JP5"
			(at 1.1176 -3.37947 0)
			(unlocked yes)
			(layer "F.SilkS")
			(effects
				(font
					(size 0.7874 0.5842)
					(thickness 0.1524)
				)
				(justify left)
			)
		)
		(property "Value" ""
			(at 0 0 180)
			(layer "F.Fab")
			(effects
				(font
					(size 1.27 1.27)
				)
			)
		)
		(duplicate_pad_numbers_are_jumpers no)
		(fp_line
			(start 1.234948 6.415024)
			(end -1.234948 6.415024)
			(stroke
				(width 0.1524)
				(type default)
			)
			(layer "F.SilkS")
		)
		(fp_line
			(start 1.234948 -1.335024)
			(end 1.234948 6.415024)
			(stroke
				(width 0.1524)
				(type default)
			)
			(layer "F.SilkS")
		)
		(fp_line
			(start -1.234948 6.415024)
			(end -1.234948 -1.335024)
			(stroke
				(width 0.1524)
				(type default)
			)
			(layer "F.SilkS")
		)
		(fp_line
			(start -1.234948 -1.335024)
			(end 1.234948 -1.335024)
			(stroke
				(width 0.1524)
				(type default)
			)
			(layer "F.SilkS")
		)
		(fp_poly
			(pts
				(xy 0.508 -2.530348) (xy -0.508 -2.530348) (xy 0 -1.514348)
			)
			(stroke
				(width 0)
				(type default)
			)
			(fill yes)
			(layer "F.SilkS")
		)
		(fp_line
			(start 1.234948 6.415024)
			(end -1.234948 6.415024)
			(stroke
				(width 0.1)
				(type default)
			)
			(layer "F.Fab")
		)
		(fp_line
			(start 1.234948 -1.335024)
			(end 1.234948 6.415024)
			(stroke
				(width 0.1)
				(type default)
			)
			(layer "F.Fab")
		)
		(fp_line
			(start -1.234948 6.415024)
			(end -1.234948 -1.335024)
			(stroke
				(width 0.1)
				(type default)
			)
			(layer "F.Fab")
		)
		(fp_line
			(start -1.234948 -1.335024)
			(end 1.234948 -1.335024)
			(stroke
				(width 0.1)
				(type default)
			)
			(layer "F.Fab")
		)
		(fp_poly
			(pts
				(xy 0.508 -2.530348) (xy -0.508 -2.530348) (xy 0 -1.514348)
			)
			(stroke
				(width 0)
				(type default)
			)
			(fill yes)
			(layer "F.Fab")
		)
		(fp_text user "3"
			(at -0.009652 6.5659 90)
			(unlocked yes)
			(layer "F.SilkS")
			(effects
				(font
					(size 0.7874 0.5842)
					(thickness 0.1524)
				)
				(justify left)
			)
		)
		(fp_text user "3"
			(at -0.00127 6.640576 90)
			(unlocked yes)
			(layer "B.SilkS")
			(effects
				(font
					(size 0.7874 0.5842)
					(thickness 0.1524)
				)
				(justify left mirror)
			)
		)
		(fp_text user "1"
			(at -0.00127 -0.954024 90)
			(unlocked yes)
			(layer "B.SilkS")
			(effects
				(font
					(size 0.7874 0.5842)
					(thickness 0.1524)
				)
				(justify left mirror)
			)
		)
		(fp_text user "3"
			(at -0.00127 6.640576 90)
			(unlocked yes)
			(layer "B.Fab")
			(effects
				(font
					(size 0.7874 0.5842)
					(thickness 0.1524)
				)
				(justify left mirror)
			)
		)
		(fp_text user "1"
			(at -0.00127 -0.954024 90)
			(unlocked yes)
			(layer "B.Fab")
			(effects
				(font
					(size 0.7874 0.5842)
					(thickness 0.1524)
				)
				(justify left mirror)
			)
		)
		(fp_text user "3"
			(at -0.009652 6.5659 90)
			(unlocked yes)
			(layer "F.Fab")
			(effects
				(font
					(size 0.7874 0.5842)
					(thickness 0.1524)
				)
				(justify left)
			)
		)
		(pad "1" thru_hole rect
			(at 0 0 90)
			(size 1.6764 1.6764)
			(drill 1.1684)
			(layers "*.Cu" "*.Mask")
			(remove_unused_layers no)
			(net "TP_P52V_HS1_EN")
			(clearance 0)
			(padstack
				(mode front_inner_back)
				(layer "Inner"
					(shape circle)
					(size 1.6764 1.6764)
					(clearance 0)
				)
				(layer "B.Cu"
					(shape rect)
					(size 1.6764 1.6764)
					(clearance 0)
				)
			)
		)
		(pad "2" thru_hole circle
			(at 0 2.54 90)
			(size 1.6764 1.6764)
			(drill 1.1684)
			(layers "*.Cu" "*.Mask")
			(remove_unused_layers no)
			(net "GPU_HSC1_BUF_EN_N")
			(clearance 0)
		)
		(pad "3" thru_hole circle
			(at 0 5.08 90)
			(size 1.6764 1.6764)
			(drill 1.1684)
			(layers "*.Cu" "*.Mask")
			(remove_unused_layers no)
			(net "GND")
			(clearance 0)
		)
	)
	(footprint ""
		(layer "F.Cu")
		(at 434.848 -41.148 -90)
		(property "Reference" "R4"
			(at 0 0 270)
			(layer "F.SilkS")
			(hide yes)
			(effects
				(font
					(size 1.27 1.27)
				)
			)
		)
		(property "Value" ""
			(at 0 0 270)
			(layer "F.Fab")
			(effects
				(font
					(size 1.27 1.27)
				)
			)
		)
		(duplicate_pad_numbers_are_jumpers no)
		(fp_line
			(start -0.7874 0.4064)
			(end -0.7874 -0.4064)
			(stroke
				(width 0.1524)
				(type default)
			)
			(layer "F.SilkS")
		)
		(fp_line
			(start 0.7874 0.4064)
			(end -0.7874 0.4064)
			(stroke
				(width 0.1524)
				(type default)
			)
			(layer "F.SilkS")
		)
		(fp_line
			(start -0.7874 -0.4064)
			(end 0.7874 -0.4064)
			(stroke
				(width 0.1524)
				(type default)
			)
			(layer "F.SilkS")
		)
		(fp_line
			(start 0.7874 -0.4064)
			(end 0.7874 0.4064)
			(stroke
				(width 0.1524)
				(type default)
			)
			(layer "F.SilkS")
		)
		(fp_line
			(start -0.67945 0.3048)
			(end -0.67945 -0.305054)
			(stroke
				(width 0.1)
				(type default)
			)
			(layer "F.Fab")
		)
		(fp_line
			(start -0.12065 0.3048)
			(end -0.67945 0.3048)
			(stroke
				(width 0.1)
				(type default)
			)
			(layer "F.Fab")
		)
		(fp_line
			(start 0.120396 0.3048)
			(end 0.120396 0.2794)
			(stroke
				(width 0.1)
				(type default)
			)
			(layer "F.Fab")
		)
		(fp_line
			(start 0.67945 0.3048)
			(end 0.120396 0.3048)
			(stroke
				(width 0.1)
				(type default)
			)
			(layer "F.Fab")
		)
		(fp_line
			(start -0.12065 0.2794)
			(end -0.12065 0.3048)
			(stroke
				(width 0.1)
				(type default)
			)
			(layer "F.Fab")
		)
		(fp_line
			(start 0.120396 0.2794)
			(end -0.12065 0.2794)
			(stroke
				(width 0.1)
				(type default)
			)
			(layer "F.Fab")
		)
		(fp_line
			(start -0.12065 -0.2794)
			(end 0.12065 -0.2794)
			(stroke
				(width 0.1)
				(type default)
			)
			(layer "F.Fab")
		)
		(fp_line
			(start 0.12065 -0.2794)
			(end 0.12065 -0.3048)
			(stroke
				(width 0.1)
				(type default)
			)
			(layer "F.Fab")
		)
		(fp_line
			(start 0.12065 -0.3048)
			(end 0.67945 -0.3048)
			(stroke
				(width 0.1)
				(type default)
			)
			(layer "F.Fab")
		)
		(fp_line
			(start 0.67945 -0.3048)
			(end 0.67945 0.3048)
			(stroke
				(width 0.1)
				(type default)
			)
			(layer "F.Fab")
		)
		(fp_line
			(start -0.67945 -0.305054)
			(end -0.12065 -0.305054)
			(stroke
				(width 0.1)
				(type default)
			)
			(layer "F.Fab")
		)
		(fp_line
			(start -0.12065 -0.305054)
			(end -0.12065 -0.2794)
			(stroke
				(width 0.1)
				(type default)
			)
			(layer "F.Fab")
		)
		(pad "1" smd circle
			(at -0.40005 0 270)
			(size 0 0)
			(layers "F.Cu" "F.Mask" "F.Paste")
			(net "SMB_PDB_MISC_SCL_R")
		)
		(pad "2" smd circle
			(at 0.40005 0 270)
			(size 0 0)
			(layers "F.Cu" "F.Mask" "F.Paste")
			(net "SMB_PDB_MISC_SCL_R1")
		)
	)
	(footprint ""
		(layer "F.Cu")
		(at 302.4124 -34.3662 180)
		(property "Reference" "PR6961"
			(at 0 0 180)
			(layer "F.SilkS")
			(hide yes)
			(effects
				(font
					(size 1.27 1.27)
				)
			)
		)
		(property "Value" ""
			(at 0 0 180)
			(layer "F.Fab")
			(effects
				(font
					(size 1.27 1.27)
				)
			)
		)
		(duplicate_pad_numbers_are_jumpers no)
		(fp_line
			(start 1.2954 0.5842)
			(end -1.2954 0.5842)
			(stroke
				(width 0.1524)
				(type default)
			)
			(layer "F.SilkS")
		)
		(fp_line
			(start 1.2954 -0.5842)
			(end 1.2954 0.5842)
			(stroke
				(width 0.1524)
				(type default)
			)
			(layer "F.SilkS")
		)
		(fp_line
			(start -1.2954 0.5842)
			(end -1.2954 -0.5842)
			(stroke
				(width 0.1524)
				(type default)
			)
			(layer "F.SilkS")
		)
		(fp_line
			(start -1.2954 -0.5842)
			(end 1.2954 -0.5842)
			(stroke
				(width 0.1524)
				(type default)
			)
			(layer "F.SilkS")
		)
		(fp_line
			(start 1.1938 0.4064)
			(end 0.8636 0.4064)
			(stroke
				(width 0.1)
				(type default)
			)
			(layer "F.Fab")
		)
		(fp_line
			(start 1.1938 -0.406654)
			(end 1.1938 0.4064)
			(stroke
				(width 0.1)
				(type default)
			)
			(layer "F.Fab")
		)
		(fp_line
			(start 0.8636 0.4572)
			(end -0.8636 0.4572)
			(stroke
				(width 0.1)
				(type default)
			)
			(layer "F.Fab")
		)
		(fp_line
			(start 0.8636 0.4064)
			(end 0.8636 0.4572)
			(stroke
				(width 0.1)
				(type default)
			)
			(layer "F.Fab")
		)
		(fp_line
			(start 0.8636 -0.406654)
			(end 1.1938 -0.406654)
			(stroke
				(width 0.1)
				(type default)
			)
			(layer "F.Fab")
		)
		(fp_line
			(start 0.8636 -0.4572)
			(end 0.8636 -0.406654)
			(stroke
				(width 0.1)
				(type default)
			)
			(layer "F.Fab")
		)
		(fp_line
			(start -0.8636 0.4572)
			(end -0.8636 0.4318)
			(stroke
				(width 0.1)
				(type default)
			)
			(layer "F.Fab")
		)
		(fp_line
			(start -0.8636 0.4318)
			(end -0.8636 0.4064)
			(stroke
				(width 0.1)
				(type default)
			)
			(layer "F.Fab")
		)
		(fp_line
			(start -0.8636 0.4064)
			(end -1.1938 0.4064)
			(stroke
				(width 0.1)
				(type default)
			)
			(layer "F.Fab")
		)
		(fp_line
			(start -0.8636 -0.406654)
			(end -0.8636 -0.4572)
			(stroke
				(width 0.1)
				(type default)
			)
			(layer "F.Fab")
		)
		(fp_line
			(start -0.8636 -0.4572)
			(end 0.8636 -0.4572)
			(stroke
				(width 0.1)
				(type default)
			)
			(layer "F.Fab")
		)
		(fp_line
			(start -1.1938 0.4064)
			(end -1.1938 -0.406654)
			(stroke
				(width 0.1)
				(type default)
			)
			(layer "F.Fab")
		)
		(fp_line
			(start -1.1938 -0.406654)
			(end -0.8636 -0.406654)
			(stroke
				(width 0.1)
				(type default)
			)
			(layer "F.Fab")
		)
		(pad "1" smd rect
			(at -0.7366 0 90)
			(size 0.7112 0.8128)
			(layers "F.Cu" "F.Mask" "F.Paste")
			(net "P52V_HS_1272_S_P")
		)
		(pad "2" smd rect
			(at 0.7366 0 90)
			(size 0.7112 0.8128)
			(layers "F.Cu" "F.Mask" "F.Paste")
			(net "P52V_HS1_SENSE_P_R2")
		)
	)
	(footprint ""
		(layer "F.Cu")
		(at 302.4124 -37.9222 180)
		(property "Reference" "PR6955"
			(at 0 0 180)
			(layer "F.SilkS")
			(hide yes)
			(effects
				(font
					(size 1.27 1.27)
				)
			)
		)
		(property "Value" ""
			(at 0 0 180)
			(layer "F.Fab")
			(effects
				(font
					(size 1.27 1.27)
				)
			)
		)
		(duplicate_pad_numbers_are_jumpers no)
		(fp_line
			(start 1.2954 0.5842)
			(end -1.2954 0.5842)
			(stroke
				(width 0.1524)
				(type default)
			)
			(layer "F.SilkS")
		)
		(fp_line
			(start 1.2954 -0.5842)
			(end 1.2954 0.5842)
			(stroke
				(width 0.1524)
				(type default)
			)
			(layer "F.SilkS")
		)
		(fp_line
			(start -1.2954 0.5842)
			(end -1.2954 -0.5842)
			(stroke
				(width 0.1524)
				(type default)
			)
			(layer "F.SilkS")
		)
		(fp_line
			(start -1.2954 -0.5842)
			(end 1.2954 -0.5842)
			(stroke
				(width 0.1524)
				(type default)
			)
			(layer "F.SilkS")
		)
		(fp_line
			(start 1.1938 0.4064)
			(end 0.8636 0.4064)
			(stroke
				(width 0.1)
				(type default)
			)
			(layer "F.Fab")
		)
		(fp_line
			(start 1.1938 -0.406654)
			(end 1.1938 0.4064)
			(stroke
				(width 0.1)
				(type default)
			)
			(layer "F.Fab")
		)
		(fp_line
			(start 0.8636 0.4572)
			(end -0.8636 0.4572)
			(stroke
				(width 0.1)
				(type default)
			)
			(layer "F.Fab")
		)
		(fp_line
			(start 0.8636 0.4064)
			(end 0.8636 0.4572)
			(stroke
				(width 0.1)
				(type default)
			)
			(layer "F.Fab")
		)
		(fp_line
			(start 0.8636 -0.406654)
			(end 1.1938 -0.406654)
			(stroke
				(width 0.1)
				(type default)
			)
			(layer "F.Fab")
		)
		(fp_line
			(start 0.8636 -0.4572)
			(end 0.8636 -0.406654)
			(stroke
				(width 0.1)
				(type default)
			)
			(layer "F.Fab")
		)
		(fp_line
			(start -0.8636 0.4572)
			(end -0.8636 0.4318)
			(stroke
				(width 0.1)
				(type default)
			)
			(layer "F.Fab")
		)
		(fp_line
			(start -0.8636 0.4318)
			(end -0.8636 0.4064)
			(stroke
				(width 0.1)
				(type default)
			)
			(layer "F.Fab")
		)
		(fp_line
			(start -0.8636 0.4064)
			(end -1.1938 0.4064)
			(stroke
				(width 0.1)
				(type default)
			)
			(layer "F.Fab")
		)
		(fp_line
			(start -0.8636 -0.406654)
			(end -0.8636 -0.4572)
			(stroke
				(width 0.1)
				(type default)
			)
			(layer "F.Fab")
		)
		(fp_line
			(start -0.8636 -0.4572)
			(end 0.8636 -0.4572)
			(stroke
				(width 0.1)
				(type default)
			)
			(layer "F.Fab")
		)
		(fp_line
			(start -1.1938 0.4064)
			(end -1.1938 -0.406654)
			(stroke
				(width 0.1)
				(type default)
			)
			(layer "F.Fab")
		)
		(fp_line
			(start -1.1938 -0.406654)
			(end -0.8636 -0.406654)
			(stroke
				(width 0.1)
				(type default)
			)
			(layer "F.Fab")
		)
		(pad "1" smd rect
			(at -0.7366 0 90)
			(size 0.7112 0.8128)
			(layers "F.Cu" "F.Mask" "F.Paste")
			(net "P52V_HS_4287_S2P")
		)
		(pad "2" smd rect
			(at 0.7366 0 90)
			(size 0.7112 0.8128)
			(layers "F.Cu" "F.Mask" "F.Paste")
			(net "P52V_HS1_SENSE_P_R2")
		)
	)
)
